# T6G (Grand Teton) — schematic netlist excerpt (pin names and nets, part order shuffled) for the footprints in the layout excerpt that follows; sources: Cadence DE-HDL packaged netlist, KiCad conversion of 04192023_DAF0TMB3IC0_F0TG_MB_C_brd_V02_OCP.brd

PL36  Q_INDUCTOR4P_14  150NH IND  pkg L_TLM117513Q-151QL_11X7-5XA  page 215
  \1\  = SW_PVDDCR_SOC_P1_SW2
  \2\  = IND_SOC_P1_CPL3
  \3\  = IND_SOC_P1_CPL2
  \4\  = PVDDCR_SOC_P1

U326  MPQ8633AGLEC807Z  MPQ8633AGLE-C807-Z IC  pkg QFN14_4X3  page 189
  BST  = SW_P5V_AUX_BST
  AGND  = GND
  CS  = P5V_AUX_CS
  MODE  = P5V_AUX_MODE
  TRK_REF  = P5V_AUX_REF
  RGND  = GND
  FB  = P5V_AUX_FB
  EN  = P5V_AUX_EN
  PGOOD  = PWRGD_P5V_AUX_R
  VIN1  = SW_P5V_AUX_FLT
  PGND  = GND
  VCC  = P5V_AUX_VCC
  SW  = SW_P5V_AUX_SW
  VIN2  = SW_P5V_AUX_FLT

(kicad_pcb
	(version 20260206)
	(generator "pcbnew")
	(generator_version "10.0")
	(general
		(thickness 1.6)
		(legacy_teardrops no)
	)
	(paper "A4")
	(title_block
		(title "04192023_DAF0TMB3IC0_F0TG_MB_C_brd_V02_OCP.brd")
		(comment 1 "Grand Teton / footprints 3116-3117 of 8354")
	)
	(layers
		(0 "F.Cu" signal "TOP")
		(4 "In1.Cu" signal "GND")
		(6 "In2.Cu" signal "IN1")
		(8 "In3.Cu" signal "GND1")
		(10 "In4.Cu" signal "IN2")
		(12 "In5.Cu" signal "GND2")
		(14 "In6.Cu" signal "IN3")
		(16 "In7.Cu" signal "GND3")
		(18 "In8.Cu" signal "VCC")
		(20 "In9.Cu" signal "VCC1")
		(22 "In10.Cu" signal "GND4")
		(24 "In11.Cu" signal "IN4")
		(26 "In12.Cu" signal "GND5")
		(28 "In13.Cu" signal "IN5")
		(30 "In14.Cu" signal "GND6")
		(32 "In15.Cu" signal "IN6")
		(34 "In16.Cu" signal "GND7")
		(2 "B.Cu" signal "BOTTOM")
		(9 "F.Adhes" user "F.Adhesive")
		(11 "B.Adhes" user "B.Adhesive")
		(13 "F.Paste" user "Package Geometry/Pastemask Top")
		(15 "B.Paste" user "Package Geometry/Pastemask Bottom")
		(5 "F.SilkS" user "Ref Des/Silkscreen Top")
		(7 "B.SilkS" user "Ref Des/Silkscreen Bottom")
		(1 "F.Mask" user "Board Geometry/Soldermask Top")
		(3 "B.Mask" user "Board Geometry/Soldermask Bottom")
		(17 "Dwgs.User" user "User.Drawings")
		(19 "Cmts.User" user "User.Comments")
		(21 "Eco1.User" user "User.Eco1")
		(23 "Eco2.User" user "User.Eco2")
		(25 "Edge.Cuts" user "Board Geometry/Outline")
		(27 "Margin" user)
		(31 "F.CrtYd" user "Package Geometry/Place Bound Top")
		(29 "B.CrtYd" user "Package Geometry/Place Bound Bottom")
		(35 "F.Fab" user "Ref Des/Assembly Top")
		(33 "B.Fab" user "Ref Des/Assembly Bottom")
	)
	(footprint ""
		(layer "F.Cu")
		(at 413.270192 -140.783056)
		(property "Reference" "U326"
			(at 4.306062 0.730758 90)
			(unlocked yes)
			(layer "F.SilkS")
			(effects
				(font
					(size 0.7874 0.5842)
					(thickness 0.1524)
				)
				(justify left)
			)
		)
		(property "Value" ""
			(at 0 0 0)
			(layer "F.Fab")
			(effects
				(font
					(size 1.27 1.27)
				)
			)
		)
		(duplicate_pad_numbers_are_jumpers no)
		(fp_line
			(start -1.549908 -2.050034)
			(end -1.549908 -1.9812)
			(stroke
				(width 0.1524)
				(type default)
			)
			(layer "F.SilkS")
		)
		(fp_line
			(start -1.549908 1.9812)
			(end -1.549908 2.050034)
			(stroke
				(width 0.1524)
				(type default)
			)
			(layer "F.SilkS")
		)
		(fp_line
			(start -1.549908 2.050034)
			(end -0.5842 2.050034)
			(stroke
				(width 0.1524)
				(type default)
			)
			(layer "F.SilkS")
		)
		(fp_line
			(start -0.5842 -2.050034)
			(end -1.549908 -2.050034)
			(stroke
				(width 0.1524)
				(type default)
			)
			(layer "F.SilkS")
		)
		(fp_line
			(start 0 2.050034)
			(end 1.549908 2.050034)
			(stroke
				(width 0.1524)
				(type default)
			)
			(layer "F.SilkS")
		)
		(fp_line
			(start 1.549908 -2.050034)
			(end 0.5842 -2.050034)
			(stroke
				(width 0.1524)
				(type default)
			)
			(layer "F.SilkS")
		)
		(fp_line
			(start 1.549908 -1.9812)
			(end 1.549908 -2.050034)
			(stroke
				(width 0.1524)
				(type default)
			)
			(layer "F.SilkS")
		)
		(fp_line
			(start 1.549908 2.050034)
			(end 1.549908 1.9304)
			(stroke
				(width 0.1524)
				(type default)
			)
			(layer "F.SilkS")
		)
		(fp_poly
			(pts
				(xy -3.364738 -3.2004) (xy -4.083304 -2.482088) (xy -3.005582 -2.122678)
			)
			(stroke
				(width 0)
				(type default)
			)
			(fill yes)
			(layer "F.SilkS")
		)
		(fp_line
			(start -1.549908 -2.050034)
			(end -1.549908 2.050034)
			(stroke
				(width 0.1)
				(type default)
			)
			(layer "F.Fab")
		)
		(fp_line
			(start -1.549908 2.050034)
			(end 1.549908 2.050034)
			(stroke
				(width 0.1)
				(type default)
			)
			(layer "F.Fab")
		)
		(fp_line
			(start 1.549908 -2.050034)
			(end -1.549908 -2.050034)
			(stroke
				(width 0.1)
				(type default)
			)
			(layer "F.Fab")
		)
		(fp_line
			(start 1.549908 2.050034)
			(end 1.549908 -2.050034)
			(stroke
				(width 0.1)
				(type default)
			)
			(layer "F.Fab")
		)
		(fp_poly
			(pts
				(xy -2.9464 -2.208022) (xy -2.9464 -1.192022) (xy -1.9304 -1.700022)
			)
			(stroke
				(width 0)
				(type default)
			)
			(fill yes)
			(layer "F.Fab")
		)
		(pad "1" smd circle
			(at -1.35001 -1.700022)
			(size 0 0)
			(layers "F.Cu" "F.Mask" "F.Paste")
			(net "SW_P5V_AUX_BST")
		)
		(pad "2" smd rect
			(at -1.400048 -1.199896 90)
			(size 0.1778 0.8128)
			(layers "F.Cu" "F.Mask" "F.Paste")
			(net "GND")
		)
		(pad "3" smd rect
			(at -1.400048 -0.8001 90)
			(size 0.1778 0.8128)
			(layers "F.Cu" "F.Mask" "F.Paste")
			(net "P5V_AUX_CS")
		)
		(pad "4" smd rect
			(at -1.400048 -0.40005 90)
			(size 0.1778 0.8128)
			(layers "F.Cu" "F.Mask" "F.Paste")
			(net "P5V_AUX_MODE")
		)
		(pad "5" smd rect
			(at -1.400048 0 90)
			(size 0.1778 0.8128)
			(layers "F.Cu" "F.Mask" "F.Paste")
			(net "P5V_AUX_REF")
		)
		(pad "6" smd rect
			(at -1.400048 0.40005 90)
			(size 0.1778 0.8128)
			(layers "F.Cu" "F.Mask" "F.Paste")
			(net "GND")
		)
		(pad "7" smd rect
			(at -1.400048 0.8001 90)
			(size 0.1778 0.8128)
			(layers "F.Cu" "F.Mask" "F.Paste")
			(net "P5V_AUX_FB")
		)
		(pad "8" smd rect
			(at -1.400048 1.199896 90)
			(size 0.1778 0.8128)
			(layers "F.Cu" "F.Mask" "F.Paste")
			(net "P5V_AUX_EN")
		)
		(pad "9" smd rect
			(at -1.400048 1.700022 90)
			(size 0.3048 0.8128)
			(layers "F.Cu" "F.Mask" "F.Paste")
			(net "PWRGD_P5V_AUX_R")
		)
		(pad "10" smd rect
			(at -0.299974 1.299972)
			(size 0.3048 2.0066)
			(layers "F.Cu" "F.Mask" "F.Paste")
			(net "SW_P5V_AUX_FLT")
		)
		(pad "11_18" smd circle
			(at 1.175004 0.275082)
			(size 0 0)
			(layers "F.Cu" "F.Mask" "F.Paste")
			(net "GND")
		)
		(pad "19" smd rect
			(at 1.400048 -1.700022 270)
			(size 0.3048 0.8128)
			(layers "F.Cu" "F.Mask" "F.Paste")
			(net "P5V_AUX_VCC")
		)
		(pad "20" smd rect
			(at 0.299974 -1.299972)
			(size 0.3048 2.0066)
			(layers "F.Cu" "F.Mask" "F.Paste")
			(net "SW_P5V_AUX_SW")
		)
		(pad "21" smd rect
			(at -0.299974 -1.299972)
			(size 0.3048 2.0066)
			(layers "F.Cu" "F.Mask" "F.Paste")
			(net "SW_P5V_AUX_FLT")
		)
	)
	(footprint ""
		(layer "F.Cu")
		(at 124.323348 -174.509684 180)
		(property "Reference" "PL36"
			(at -0.772668 6.156198 0)
			(unlocked yes)
			(layer "F.SilkS")
			(effects
				(font
					(size 0.7874 0.5842)
					(thickness 0.1524)
				)
				(justify left)
			)
		)
		(property "Value" ""
			(at 0 0 180)
			(layer "F.Fab")
			(effects
				(font
					(size 1.27 1.27)
				)
			)
		)
		(duplicate_pad_numbers_are_jumpers no)
		(fp_line
			(start 3.750056 5.500116)
			(end 3.750056 -5.500116)
			(stroke
				(width 0.1524)
				(type default)
			)
			(layer "F.SilkS")
		)
		(fp_line
			(start 3.750056 -5.500116)
			(end 2.393442 -5.500116)
			(stroke
				(width 0.1524)
				(type default)
			)
			(layer "F.SilkS")
		)
		(fp_line
			(start 2.393442 5.500116)
			(end 3.750056 5.500116)
			(stroke
				(width 0.1524)
				(type default)
			)
			(layer "F.SilkS")
		)
		(fp_line
			(start -2.393442 5.500116)
			(end -3.750056 5.500116)
			(stroke
				(width 0.1524)
				(type default)
			)
			(layer "F.SilkS")
		)
		(fp_line
			(start -3.750056 5.500116)
			(end -3.750056 -5.500116)
			(stroke
				(width 0.1524)
				(type default)
			)
			(layer "F.SilkS")
		)
		(fp_line
			(start -3.750056 -5.500116)
			(end -2.393442 -5.500116)
			(stroke
				(width 0.1524)
				(type default)
			)
			(layer "F.SilkS")
		)
		(fp_poly
			(pts
				(xy -3.9116 -4.249928) (xy -4.3434 -4.034028) (xy -4.3434 -4.465828)
			)
			(stroke
				(width 0)
				(type default)
			)
			(fill yes)
			(layer "F.SilkS")
		)
		(fp_line
			(start 3.750056 5.500116)
			(end 3.750056 -5.500116)
			(stroke
				(width 0.1)
				(type default)
			)
			(layer "F.Fab")
		)
		(fp_line
			(start 3.750056 -5.500116)
			(end -3.750056 -5.500116)
			(stroke
				(width 0.1)
				(type default)
			)
			(layer "F.Fab")
		)
		(fp_line
			(start -3.750056 5.500116)
			(end 3.750056 5.500116)
			(stroke
				(width 0.1)
				(type default)
			)
			(layer "F.Fab")
		)
		(fp_line
			(start -3.750056 -5.500116)
			(end -3.750056 5.500116)
			(stroke
				(width 0.1)
				(type default)
			)
			(layer "F.Fab")
		)
		(fp_poly
			(pts
				(xy -4.9276 -4.757928) (xy -4.9276 -3.741928) (xy -3.9116 -4.249928)
			)
			(stroke
				(width 0)
				(type default)
			)
			(fill yes)
			(layer "F.Fab")
		)
		(pad "1" smd rect
			(at 0 -4.249928 90)
			(size 2.413 4.5212)
			(layers "F.Cu" "F.Mask" "F.Paste")
			(net "SW_PVDDCR_SOC_P1_SW2")
		)
		(pad "2" smd rect
			(at 0 -1.175004 90)
			(size 1.3716 4.5212)
			(layers "F.Cu" "F.Mask" "F.Paste")
			(net "IND_SOC_P1_CPL3")
		)
		(pad "3" smd rect
			(at 0 1.175004 90)
			(size 1.3716 4.5212)
			(layers "F.Cu" "F.Mask" "F.Paste")
			(net "IND_SOC_P1_CPL2")
		)
		(pad "4" smd rect
			(at 0 4.249928 90)
			(size 2.413 4.5212)
			(layers "F.Cu" "F.Mask" "F.Paste")
			(net "PVDDCR_SOC_P1")
		)
	)
)
